# T6G (Grand Teton) — schematic netlist excerpt (pin names and nets, part order shuffled) for the footprints in the layout excerpt that follows; sources: Cadence DE-HDL packaged netlist, KiCad conversion of 04192023_DAF0TMB3IC0_F0TG_MB_C_brd_V02_OCP.brd

PC112  Q_CAP  2.2UF 10V 10% X6S  pkg C0402  page 203 : A = PVDDCR_CPU1_P0_VCC6 ; B = GND
PR8000  Q_RES  0 5% CHIP  pkg 0402LF  page 192 : A = SW_PVDD_33_S5_BST ; B = SW_PVDD_33_S5_BST_R

(kicad_pcb
	(version 20260206)
	(generator "pcbnew")
	(generator_version "10.0")
	(general
		(thickness 1.6)
		(legacy_teardrops no)
	)
	(paper "A4")
	(title_block
		(title "04192023_DAF0TMB3IC0_F0TG_MB_C_brd_V02_OCP.brd")
		(comment 1 "Grand Teton / footprints 3860-3861 of 8354")
	)
	(layers
		(0 "F.Cu" signal "TOP")
		(4 "In1.Cu" signal "GND")
		(6 "In2.Cu" signal "IN1")
		(8 "In3.Cu" signal "GND1")
		(10 "In4.Cu" signal "IN2")
		(12 "In5.Cu" signal "GND2")
		(14 "In6.Cu" signal "IN3")
		(16 "In7.Cu" signal "GND3")
		(18 "In8.Cu" signal "VCC")
		(20 "In9.Cu" signal "VCC1")
		(22 "In10.Cu" signal "GND4")
		(24 "In11.Cu" signal "IN4")
		(26 "In12.Cu" signal "GND5")
		(28 "In13.Cu" signal "IN5")
		(30 "In14.Cu" signal "GND6")
		(32 "In15.Cu" signal "IN6")
		(34 "In16.Cu" signal "GND7")
		(2 "B.Cu" signal "BOTTOM")
		(9 "F.Adhes" user "F.Adhesive")
		(11 "B.Adhes" user "B.Adhesive")
		(13 "F.Paste" user "Package Geometry/Pastemask Top")
		(15 "B.Paste" user "Package Geometry/Pastemask Bottom")
		(5 "F.SilkS" user "Ref Des/Silkscreen Top")
		(7 "B.SilkS" user "Ref Des/Silkscreen Bottom")
		(1 "F.Mask" user "Board Geometry/Soldermask Top")
		(3 "B.Mask" user "Board Geometry/Soldermask Bottom")
		(17 "Dwgs.User" user "User.Drawings")
		(19 "Cmts.User" user "User.Comments")
		(21 "Eco1.User" user "User.Eco1")
		(23 "Eco2.User" user "User.Eco2")
		(25 "Edge.Cuts" user "Board Geometry/Outline")
		(27 "Margin" user)
		(31 "F.CrtYd" user "Package Geometry/Place Bound Top")
		(29 "B.CrtYd" user "Package Geometry/Place Bound Bottom")
		(35 "F.Fab" user "Ref Des/Assembly Top")
		(33 "B.Fab" user "Ref Des/Assembly Bottom")
	)
	(footprint ""
		(layer "F.Cu")
		(at 203.454 -337.82)
		(property "Reference" "PR8000"
			(at 0 0 0)
			(layer "F.SilkS")
			(hide yes)
			(effects
				(font
					(size 1.27 1.27)
				)
			)
		)
		(property "Value" ""
			(at 0 0 0)
			(layer "F.Fab")
			(effects
				(font
					(size 1.27 1.27)
				)
			)
		)
		(duplicate_pad_numbers_are_jumpers no)
		(fp_line
			(start -0.7874 -0.4064)
			(end 0.7874 -0.4064)
			(stroke
				(width 0.1524)
				(type default)
			)
			(layer "F.SilkS")
		)
		(fp_line
			(start -0.7874 0.4064)
			(end -0.7874 -0.4064)
			(stroke
				(width 0.1524)
				(type default)
			)
			(layer "F.SilkS")
		)
		(fp_line
			(start 0.7874 -0.4064)
			(end 0.7874 0.4064)
			(stroke
				(width 0.1524)
				(type default)
			)
			(layer "F.SilkS")
		)
		(fp_line
			(start 0.7874 0.4064)
			(end -0.7874 0.4064)
			(stroke
				(width 0.1524)
				(type default)
			)
			(layer "F.SilkS")
		)
		(fp_line
			(start -0.67945 -0.305054)
			(end -0.12065 -0.305054)
			(stroke
				(width 0.1)
				(type default)
			)
			(layer "F.Fab")
		)
		(fp_line
			(start -0.67945 0.3048)
			(end -0.67945 -0.305054)
			(stroke
				(width 0.1)
				(type default)
			)
			(layer "F.Fab")
		)
		(fp_line
			(start -0.12065 -0.305054)
			(end -0.12065 -0.2794)
			(stroke
				(width 0.1)
				(type default)
			)
			(layer "F.Fab")
		)
		(fp_line
			(start -0.12065 -0.2794)
			(end 0.12065 -0.2794)
			(stroke
				(width 0.1)
				(type default)
			)
			(layer "F.Fab")
		)
		(fp_line
			(start -0.12065 0.2794)
			(end -0.12065 0.3048)
			(stroke
				(width 0.1)
				(type default)
			)
			(layer "F.Fab")
		)
		(fp_line
			(start -0.12065 0.3048)
			(end -0.67945 0.3048)
			(stroke
				(width 0.1)
				(type default)
			)
			(layer "F.Fab")
		)
		(fp_line
			(start 0.120396 0.2794)
			(end -0.12065 0.2794)
			(stroke
				(width 0.1)
				(type default)
			)
			(layer "F.Fab")
		)
		(fp_line
			(start 0.120396 0.3048)
			(end 0.120396 0.2794)
			(stroke
				(width 0.1)
				(type default)
			)
			(layer "F.Fab")
		)
		(fp_line
			(start 0.12065 -0.3048)
			(end 0.67945 -0.3048)
			(stroke
				(width 0.1)
				(type default)
			)
			(layer "F.Fab")
		)
		(fp_line
			(start 0.12065 -0.2794)
			(end 0.12065 -0.3048)
			(stroke
				(width 0.1)
				(type default)
			)
			(layer "F.Fab")
		)
		(fp_line
			(start 0.67945 -0.3048)
			(end 0.67945 0.3048)
			(stroke
				(width 0.1)
				(type default)
			)
			(layer "F.Fab")
		)
		(fp_line
			(start 0.67945 0.3048)
			(end 0.120396 0.3048)
			(stroke
				(width 0.1)
				(type default)
			)
			(layer "F.Fab")
		)
		(pad "1" smd circle
			(at -0.40005 0)
			(size 0 0)
			(layers "F.Cu" "F.Mask" "F.Paste")
			(net "SW_PVDD_33_S5_BST")
		)
		(pad "2" smd circle
			(at 0.40005 0)
			(size 0 0)
			(layers "F.Cu" "F.Mask" "F.Paste")
			(net "SW_PVDD_33_S5_BST_R")
		)
	)
	(footprint ""
		(layer "F.Cu")
		(at 347.983048 -342.599772 90)
		(property "Reference" "PC112"
			(at 0 0 90)
			(layer "F.SilkS")
			(hide yes)
			(effects
				(font
					(size 1.27 1.27)
				)
			)
		)
		(property "Value" ""
			(at 0 0 90)
			(layer "F.Fab")
			(effects
				(font
					(size 1.27 1.27)
				)
			)
		)
		(duplicate_pad_numbers_are_jumpers no)
		(fp_line
			(start 0.7874 -0.4064)
			(end 0.7874 0.4064)
			(stroke
				(width 0.1524)
				(type default)
			)
			(layer "F.SilkS")
		)
		(fp_line
			(start -0.7874 -0.4064)
			(end 0.7874 -0.4064)
			(stroke
				(width 0.1524)
				(type default)
			)
			(layer "F.SilkS")
		)
		(fp_line
			(start 0.7874 0.4064)
			(end 0.376428 0.4064)
			(stroke
				(width 0.1524)
				(type default)
			)
			(layer "F.SilkS")
		)
		(fp_line
			(start -0.182372 0.4064)
			(end -0.7874 0.4064)
			(stroke
				(width 0.1524)
				(type default)
			)
			(layer "F.SilkS")
		)
		(fp_line
			(start -0.7874 0.4064)
			(end -0.7874 -0.4064)
			(stroke
				(width 0.1524)
				(type default)
			)
			(layer "F.SilkS")
		)
		(fp_line
			(start -0.12065 -0.305054)
			(end -0.12065 -0.2794)
			(stroke
				(width 0.1)
				(type default)
			)
			(layer "F.Fab")
		)
		(fp_line
			(start -0.67945 -0.305054)
			(end -0.12065 -0.305054)
			(stroke
				(width 0.1)
				(type default)
			)
			(layer "F.Fab")
		)
		(fp_line
			(start 0.67945 -0.3048)
			(end 0.67945 0.3048)
			(stroke
				(width 0.1)
				(type default)
			)
			(layer "F.Fab")
		)
		(fp_line
			(start 0.12065 -0.3048)
			(end 0.67945 -0.3048)
			(stroke
				(width 0.1)
				(type default)
			)
			(layer "F.Fab")
		)
		(fp_line
			(start 0.12065 -0.2794)
			(end 0.12065 -0.3048)
			(stroke
				(width 0.1)
				(type default)
			)
			(layer "F.Fab")
		)
		(fp_line
			(start -0.12065 -0.2794)
			(end 0.12065 -0.2794)
			(stroke
				(width 0.1)
				(type default)
			)
			(layer "F.Fab")
		)
		(fp_line
			(start 0.120396 0.2794)
			(end -0.12065 0.2794)
			(stroke
				(width 0.1)
				(type default)
			)
			(layer "F.Fab")
		)
		(fp_line
			(start -0.12065 0.2794)
			(end -0.12065 0.3048)
			(stroke
				(width 0.1)
				(type default)
			)
			(layer "F.Fab")
		)
		(fp_line
			(start 0.67945 0.3048)
			(end 0.120396 0.3048)
			(stroke
				(width 0.1)
				(type default)
			)
			(layer "F.Fab")
		)
		(fp_line
			(start 0.120396 0.3048)
			(end 0.120396 0.2794)
			(stroke
				(width 0.1)
				(type default)
			)
			(layer "F.Fab")
		)
		(fp_line
			(start -0.12065 0.3048)
			(end -0.67945 0.3048)
			(stroke
				(width 0.1)
				(type default)
			)
			(layer "F.Fab")
		)
		(fp_line
			(start -0.67945 0.3048)
			(end -0.67945 -0.305054)
			(stroke
				(width 0.1)
				(type default)
			)
			(layer "F.Fab")
		)
		(pad "1" smd circle
			(at -0.40005 0 90)
			(size 0 0)
			(layers "F.Cu" "F.Mask" "F.Paste")
			(net "PVDDCR_CPU1_P0_VCC6")
		)
		(pad "2" smd circle
			(at 0.40005 0 90)
			(size 0 0)
			(layers "F.Cu" "F.Mask" "F.Paste")
			(net "GND")
		)
	)
)
